# BASEBOARD_FAB2 (Tioga Pass) — schematic netlist excerpt (pin names and nets, part order shuffled) for the footprints in the layout excerpt that follows; sources: Cadence DE-HDL packaged netlist, KiCad conversion of Wiwynn_Tioga_Pass_MB.brd

Q9T1  NPN  MMBT3904 IC  pkg SM  page 181
  B  = FM_MATED_IN_D2_N
  E  = GND
  C  = FM_P12V_HOTSWAP0_EN

EU2T1  SLG55021  IC  pkg SM  page 198
  VCC  = P5V_STBY
  \on\  = FM_P3V3_CPLD_EN
  SHDN_N  = P5V_STBY
  GND  = GND
  D  = P3V3_STBY
  S  = P3V3
  G  = P3V3_SWITCH_G
  PG  = TP_SLG55021_P3V3_8
  THPAD  = GND

C1R6  CAP  0.22UF 16V 10% X7R  pkg 0402  page 106 : A = P3E_CPU0_PE3_OCP_TXP<2> ; B = P3E_OCP_CPU0_PE3_C_TXP<2>

(kicad_pcb
	(version 20260206)
	(generator "pcbnew")
	(generator_version "10.0")
	(general
		(thickness 1.6)
		(legacy_teardrops no)
	)
	(paper "A4")
	(title_block
		(title "Wiwynn_Tioga_Pass_MB.brd")
		(comment 1 "Tioga Pass / footprints 4008-4010 of 4770")
	)
	(layers
		(0 "F.Cu" signal "TOP")
		(4 "In1.Cu" signal "L2GND")
		(6 "In2.Cu" signal "L3")
		(8 "In3.Cu" signal "L4GND")
		(10 "In4.Cu" signal "L5")
		(12 "In5.Cu" signal "L6GND")
		(14 "In6.Cu" signal "L7VCC")
		(16 "In7.Cu" signal "L8VCC")
		(18 "In8.Cu" signal "L9GND")
		(20 "In9.Cu" signal "L10")
		(22 "In10.Cu" signal "L11GND")
		(24 "In11.Cu" signal "L12")
		(26 "In12.Cu" signal "L13GND")
		(2 "B.Cu" signal "BOTTOM")
		(9 "F.Adhes" user "F.Adhesive")
		(11 "B.Adhes" user "B.Adhesive")
		(13 "F.Paste" user "Package Geometry/Pastemask Top")
		(15 "B.Paste" user "Package Geometry/Pastemask Bottom")
		(5 "F.SilkS" user "Ref Des/Silkscreen Top")
		(7 "B.SilkS" user "Ref Des/Silkscreen Bottom")
		(1 "F.Mask" user "Board Geometry/Soldermask Top")
		(3 "B.Mask" user "Board Geometry/Soldermask Bottom")
		(17 "Dwgs.User" user "User.Drawings")
		(19 "Cmts.User" user "User.Comments")
		(21 "Eco1.User" user "User.Eco1")
		(23 "Eco2.User" user "User.Eco2")
		(25 "Edge.Cuts" user "Board Geometry/Outline")
		(27 "Margin" user)
		(31 "F.CrtYd" user "Package Geometry/Place Bound Top")
		(29 "B.CrtYd" user "Package Geometry/Place Bound Bottom")
		(35 "F.Fab" user "Ref Des/Assembly Top")
		(33 "B.Fab" user "Ref Des/Assembly Bottom")
	)
	(footprint ""
		(layer "B.Cu")
		(at 475.484952 -14.0589 90)
		(property "Reference" "EU2T1"
			(at 1.40843 2.0574 0)
			(unlocked yes)
			(layer "B.SilkS")
			(effects
				(font
					(size 0.7874 0.5842)
					(thickness 0.1524)
				)
				(justify left mirror)
			)
		)
		(property "Value" ""
			(at 0 0 90)
			(layer "B.Fab")
			(effects
				(font
					(size 1.27 1.27)
				)
				(justify mirror)
			)
		)
		(duplicate_pad_numbers_are_jumpers no)
		(fp_circle
			(center 0.702056 -0.595376)
			(end 0.702056 -0.468376)
			(stroke
				(width 0.254)
				(type default)
			)
			(fill no)
			(layer "B.SilkS")
		)
		(fp_rect
			(start -1.4732 1.549908)
			(end -0.5842 -0.050292)
			(stroke
				(width 0)
				(type default)
			)
			(fill yes)
			(layer "B.Paste")
		)
		(fp_rect
			(start -2.078736 1.799844)
			(end 0.021336 -0.300228)
			(stroke
				(width 0)
				(type default)
			)
			(fill no)
			(layer "B.CrtYd")
		)
		(fp_line
			(start 0.021336 -0.300228)
			(end -2.078736 -0.300228)
			(stroke
				(width 0.1)
				(type default)
			)
			(layer "B.Fab")
		)
		(fp_line
			(start -2.078736 -0.300228)
			(end -2.078736 1.799844)
			(stroke
				(width 0.1)
				(type default)
			)
			(layer "B.Fab")
		)
		(fp_line
			(start 0.021336 1.799844)
			(end 0.021336 -0.300228)
			(stroke
				(width 0.1)
				(type default)
			)
			(layer "B.Fab")
		)
		(fp_line
			(start -2.078736 1.799844)
			(end 0.021336 1.799844)
			(stroke
				(width 0.1)
				(type default)
			)
			(layer "B.Fab")
		)
		(fp_circle
			(center 0.702056 -0.595376)
			(end 0.702056 -0.468376)
			(stroke
				(width 0.254)
				(type default)
			)
			(fill no)
			(layer "B.Fab")
		)
		(pad "1" smd rect
			(at 0 0 270)
			(size 0.6604 0.3048)
			(layers "B.Cu" "B.Mask" "B.Paste")
			(net "P5V_STBY")
		)
		(pad "2" smd rect
			(at 0 0.499872 270)
			(size 0.6604 0.3048)
			(layers "B.Cu" "B.Mask" "B.Paste")
			(net "FM_P3V3_CPLD_EN")
		)
		(pad "3" smd rect
			(at 0 0.999744 270)
			(size 0.6604 0.3048)
			(layers "B.Cu" "B.Mask" "B.Paste")
			(net "P5V_STBY")
		)
		(pad "4" smd rect
			(at 0 1.499616 270)
			(size 0.6604 0.3048)
			(layers "B.Cu" "B.Mask" "B.Paste")
			(net "GND")
		)
		(pad "5" smd rect
			(at -2.0574 1.499616 270)
			(size 0.6604 0.3048)
			(layers "B.Cu" "B.Mask" "B.Paste")
			(net "P3V3_STBY")
		)
		(pad "6" smd rect
			(at -2.0574 0.999744 270)
			(size 0.6604 0.3048)
			(layers "B.Cu" "B.Mask" "B.Paste")
			(net "P3V3")
		)
		(pad "7" smd rect
			(at -2.0574 0.499872 270)
			(size 0.6604 0.3048)
			(layers "B.Cu" "B.Mask" "B.Paste")
			(net "P3V3_SWITCH_G")
		)
		(pad "8" smd rect
			(at -2.0574 0 270)
			(size 0.6604 0.3048)
			(layers "B.Cu" "B.Mask" "B.Paste")
			(net "TP_SLG55021_P3V3_8")
		)
		(pad "9" smd rect
			(at -1.0287 0.749808 270)
			(size 0.889 1.6002)
			(layers "B.Cu" "B.Mask" "B.Paste")
			(net "GND")
		)
	)
	(footprint ""
		(layer "B.Cu")
		(at 20.7264 -31.6738 90)
		(property "Reference" "Q9T1"
			(at 1.37033 2.921 0)
			(unlocked yes)
			(layer "B.SilkS")
			(effects
				(font
					(size 0.7874 0.5842)
					(thickness 0.1524)
				)
				(justify left mirror)
			)
		)
		(property "Value" ""
			(at 0 0 90)
			(layer "B.Fab")
			(effects
				(font
					(size 1.27 1.27)
				)
				(justify mirror)
			)
		)
		(duplicate_pad_numbers_are_jumpers no)
		(fp_line
			(start -0.9525 -0.5715)
			(end -1.778 -0.5715)
			(stroke
				(width 0.1524)
				(type default)
			)
			(layer "B.SilkS")
		)
		(fp_line
			(start -1.778 -0.5715)
			(end -1.778 0.3175)
			(stroke
				(width 0.1524)
				(type default)
			)
			(layer "B.SilkS")
		)
		(fp_line
			(start -0.381 0.635)
			(end -0.381 1.27)
			(stroke
				(width 0.1524)
				(type default)
			)
			(layer "B.SilkS")
		)
		(fp_line
			(start -0.9525 2.4765)
			(end -1.778 2.4765)
			(stroke
				(width 0.1524)
				(type default)
			)
			(layer "B.SilkS")
		)
		(fp_line
			(start -1.778 2.4765)
			(end -1.778 1.5875)
			(stroke
				(width 0.1524)
				(type default)
			)
			(layer "B.SilkS")
		)
		(fp_circle
			(center 0.9525 -0.9271)
			(end 0.9525 -0.8001)
			(stroke
				(width 0.254)
				(type default)
			)
			(fill no)
			(layer "B.SilkS")
		)
		(fp_poly
			(pts
				(xy -1.778 2.4765) (xy -0.381 2.4765) (xy -0.381 -0.5715) (xy -1.778 -0.5715)
			)
			(stroke
				(width 0)
				(type default)
			)
			(fill no)
			(layer "B.CrtYd")
		)
		(fp_line
			(start -0.381 -0.5715)
			(end -0.381 2.4765)
			(stroke
				(width 0.1)
				(type default)
			)
			(layer "B.Fab")
		)
		(fp_line
			(start -1.778 -0.5715)
			(end -0.381 -0.5715)
			(stroke
				(width 0.1)
				(type default)
			)
			(layer "B.Fab")
		)
		(fp_line
			(start -0.381 2.4765)
			(end -1.778 2.4765)
			(stroke
				(width 0.1)
				(type default)
			)
			(layer "B.Fab")
		)
		(fp_line
			(start -1.778 2.4765)
			(end -1.778 -0.5715)
			(stroke
				(width 0.1)
				(type default)
			)
			(layer "B.Fab")
		)
		(fp_circle
			(center 0.9525 -0.9271)
			(end 0.9525 -0.8001)
			(stroke
				(width 0.254)
				(type default)
			)
			(fill no)
			(layer "B.Fab")
		)
		(pad "1" smd rect
			(at 0 0 270)
			(size 1.143 0.508)
			(layers "B.Cu" "B.Mask" "B.Paste")
			(net "FM_MATED_IN_D2_N")
		)
		(pad "2" smd rect
			(at 0 1.905 270)
			(size 1.143 0.508)
			(layers "B.Cu" "B.Mask" "B.Paste")
			(net "GND")
		)
		(pad "3" smd rect
			(at -2.159 0.9525 270)
			(size 1.143 0.508)
			(layers "B.Cu" "B.Mask" "B.Paste")
			(net "FM_P12V_HOTSWAP0_EN")
		)
	)
	(footprint ""
		(layer "B.Cu")
		(at 456.4888 -52.483258)
		(property "Reference" "C1R6"
			(at 0 0 0)
			(layer "B.SilkS")
			(hide yes)
			(effects
				(font
					(size 1.27 1.27)
				)
				(justify mirror)
			)
		)
		(property "Value" ""
			(at 0 0 0)
			(layer "B.Fab")
			(effects
				(font
					(size 1.27 1.27)
				)
				(justify mirror)
			)
		)
		(duplicate_pad_numbers_are_jumpers no)
		(fp_poly
			(pts
				(xy -0.3048 -0.1016) (xy -0.3048 0.9906) (xy 0.3048 0.9906) (xy 0.3048 -0.1016)
			)
			(stroke
				(width 0)
				(type default)
			)
			(fill no)
			(layer "B.CrtYd")
		)
		(fp_line
			(start -0.3048 -0.1016)
			(end 0.3048 -0.1016)
			(stroke
				(width 0.1)
				(type default)
			)
			(layer "B.Fab")
		)
		(fp_line
			(start -0.3048 0.9906)
			(end -0.3048 -0.1016)
			(stroke
				(width 0.1)
				(type default)
			)
			(layer "B.Fab")
		)
		(fp_line
			(start 0.3048 -0.1016)
			(end 0.3048 0.9906)
			(stroke
				(width 0.1)
				(type default)
			)
			(layer "B.Fab")
		)
		(fp_line
			(start 0.3048 0.9906)
			(end -0.3048 0.9906)
			(stroke
				(width 0.1)
				(type default)
			)
			(layer "B.Fab")
		)
		(pad "1" smd rect
			(at 0 0 180)
			(size 0.508 0.508)
			(layers "B.Cu" "B.Mask" "B.Paste")
			(net "P3E_CPU0_PE3_OCP_TXP<2>")
		)
		(pad "2" smd rect
			(at 0 0.889 180)
			(size 0.508 0.508)
			(layers "B.Cu" "B.Mask" "B.Paste")
			(net "P3E_OCP_CPU0_PE3_C_TXP<2>")
		)
		(zone
			(layer "B.Cu")
			(hatch none 0.5)
			(connect_pads
				(clearance 0)
			)
			(min_thickness 0.25)
			(keepout
				(tracks allowed)
				(vias not_allowed)
				(pads allowed)
				(copperpour not_allowed)
				(footprints allowed)
			)
			(placement
				(enabled no)
				(sheetname "")
			)
			(fill
				(thermal_gap 0.5)
				(thermal_bridge_width 0.5)
				(island_removal_mode 0)
			)
			(polygon
				(pts
					(xy 456.7428 -52.229258) (xy 456.2348 -52.229258) (xy 456.2348 -51.848258) (xy 456.7428 -51.848258)
				)
			)
		)
	)
)
